FILE_TYPE = CONNECTIVITY;
{Allegro Design Entry HDL 17.2-2016 S081 (4005846) 1/11/2022}
"PAGE_NUMBER" = 66;
0"NC";
END.
